# SCM (Grand Teton) — schematic netlist excerpt (pin names and nets, part order shuffled) for the footprints in the layout excerpt that follows; sources: Cadence DE-HDL packaged netlist, KiCad conversion of 12092022_DA0F0TMDCD0_F0T_Management_Board_D_brd_V3_OCP.brd

C61  Q_CAP  1UF 25V 10% X6S  pkg C0402  page 16 : A = P1V8_STBY_PE_VCC18A ; B = GND
R724  Q_RES  33.2 1% CHIP  pkg 0402LF  page 44 : A = SPI_BMC_BIOS_ROM_IO2 ; B = SPI_BMC_BIOS_ROM_R_IO2

(kicad_pcb
	(version 20260206)
	(generator "pcbnew")
	(generator_version "10.0")
	(general
		(thickness 1.6)
		(legacy_teardrops no)
	)
	(paper "A4")
	(title_block
		(title "12092022_DA0F0TMDCD0_F0T_Management_Board_D_brd_V3_OCP.brd")
		(comment 1 "Grand Teton / footprints 569-570 of 1440")
	)
	(layers
		(0 "F.Cu" signal "TOP")
		(4 "In1.Cu" signal "GND")
		(6 "In2.Cu" signal "IN1")
		(8 "In3.Cu" signal "GND1")
		(10 "In4.Cu" signal "IN2")
		(12 "In5.Cu" signal "VCC")
		(14 "In6.Cu" signal "VCC1")
		(16 "In7.Cu" signal "IN3")
		(18 "In8.Cu" signal "GND2")
		(20 "In9.Cu" signal "IN4")
		(22 "In10.Cu" signal "GND3")
		(2 "B.Cu" signal "BOTTOM")
		(9 "F.Adhes" user "F.Adhesive")
		(11 "B.Adhes" user "B.Adhesive")
		(13 "F.Paste" user "Package Geometry/Pastemask Top")
		(15 "B.Paste" user "Package Geometry/Pastemask Bottom")
		(5 "F.SilkS" user "Ref Des/Silkscreen Top")
		(7 "B.SilkS" user "Ref Des/Silkscreen Bottom")
		(1 "F.Mask" user "Board Geometry/Soldermask Top")
		(3 "B.Mask" user "Board Geometry/Soldermask Bottom")
		(17 "Dwgs.User" user "User.Drawings")
		(19 "Cmts.User" user "User.Comments")
		(21 "Eco1.User" user "User.Eco1")
		(23 "Eco2.User" user "User.Eco2")
		(25 "Edge.Cuts" user "Board Geometry/Outline")
		(27 "Margin" user)
		(31 "F.CrtYd" user "Package Geometry/Place Bound Top")
		(29 "B.CrtYd" user "Package Geometry/Place Bound Bottom")
		(35 "F.Fab" user "Ref Des/Assembly Top")
		(33 "B.Fab" user "Ref Des/Assembly Bottom")
	)
	(footprint ""
		(layer "F.Cu")
		(at 59.7154 -64.0588 90)
		(property "Reference" "R724"
			(at 0 0 90)
			(layer "F.SilkS")
			(hide yes)
			(effects
				(font
					(size 1.27 1.27)
				)
			)
		)
		(property "Value" ""
			(at 0 0 90)
			(layer "F.Fab")
			(effects
				(font
					(size 1.27 1.27)
				)
			)
		)
		(duplicate_pad_numbers_are_jumpers no)
		(fp_line
			(start 0.7874 -0.4064)
			(end 0.7874 0.4064)
			(stroke
				(width 0.1524)
				(type default)
			)
			(layer "F.SilkS")
		)
		(fp_line
			(start -0.7874 -0.4064)
			(end 0.7874 -0.4064)
			(stroke
				(width 0.1524)
				(type default)
			)
			(layer "F.SilkS")
		)
		(fp_line
			(start 0.7874 0.4064)
			(end -0.7874 0.4064)
			(stroke
				(width 0.1524)
				(type default)
			)
			(layer "F.SilkS")
		)
		(fp_line
			(start -0.7874 0.4064)
			(end -0.7874 -0.4064)
			(stroke
				(width 0.1524)
				(type default)
			)
			(layer "F.SilkS")
		)
		(fp_line
			(start -0.12065 -0.305054)
			(end -0.12065 -0.2794)
			(stroke
				(width 0.1)
				(type default)
			)
			(layer "F.Fab")
		)
		(fp_line
			(start -0.67945 -0.305054)
			(end -0.12065 -0.305054)
			(stroke
				(width 0.1)
				(type default)
			)
			(layer "F.Fab")
		)
		(fp_line
			(start 0.67945 -0.3048)
			(end 0.67945 0.3048)
			(stroke
				(width 0.1)
				(type default)
			)
			(layer "F.Fab")
		)
		(fp_line
			(start 0.12065 -0.3048)
			(end 0.67945 -0.3048)
			(stroke
				(width 0.1)
				(type default)
			)
			(layer "F.Fab")
		)
		(fp_line
			(start 0.12065 -0.2794)
			(end 0.12065 -0.3048)
			(stroke
				(width 0.1)
				(type default)
			)
			(layer "F.Fab")
		)
		(fp_line
			(start -0.12065 -0.2794)
			(end 0.12065 -0.2794)
			(stroke
				(width 0.1)
				(type default)
			)
			(layer "F.Fab")
		)
		(fp_line
			(start 0.120396 0.2794)
			(end -0.12065 0.2794)
			(stroke
				(width 0.1)
				(type default)
			)
			(layer "F.Fab")
		)
		(fp_line
			(start -0.12065 0.2794)
			(end -0.12065 0.3048)
			(stroke
				(width 0.1)
				(type default)
			)
			(layer "F.Fab")
		)
		(fp_line
			(start 0.67945 0.3048)
			(end 0.120396 0.3048)
			(stroke
				(width 0.1)
				(type default)
			)
			(layer "F.Fab")
		)
		(fp_line
			(start 0.120396 0.3048)
			(end 0.120396 0.2794)
			(stroke
				(width 0.1)
				(type default)
			)
			(layer "F.Fab")
		)
		(fp_line
			(start -0.12065 0.3048)
			(end -0.67945 0.3048)
			(stroke
				(width 0.1)
				(type default)
			)
			(layer "F.Fab")
		)
		(fp_line
			(start -0.67945 0.3048)
			(end -0.67945 -0.305054)
			(stroke
				(width 0.1)
				(type default)
			)
			(layer "F.Fab")
		)
		(pad "1" smd circle
			(at -0.40005 0 90)
			(size 0 0)
			(layers "F.Cu" "F.Mask" "F.Paste")
			(net "SPI_BMC_BIOS_ROM_IO2")
		)
		(pad "2" smd circle
			(at 0.40005 0 90)
			(size 0 0)
			(layers "F.Cu" "F.Mask" "F.Paste")
			(net "SPI_BMC_BIOS_ROM_R_IO2")
		)
	)
	(footprint ""
		(layer "F.Cu")
		(at 71.013828 -62.776608 -90)
		(property "Reference" "C61"
			(at 0 0 270)
			(layer "F.SilkS")
			(hide yes)
			(effects
				(font
					(size 1.27 1.27)
				)
			)
		)
		(property "Value" ""
			(at 0 0 270)
			(layer "F.Fab")
			(effects
				(font
					(size 1.27 1.27)
				)
			)
		)
		(duplicate_pad_numbers_are_jumpers no)
		(fp_line
			(start -0.7874 0.4064)
			(end -0.7874 -0.4064)
			(stroke
				(width 0.1524)
				(type default)
			)
			(layer "F.SilkS")
		)
		(fp_line
			(start 0.7874 0.4064)
			(end -0.7874 0.4064)
			(stroke
				(width 0.1524)
				(type default)
			)
			(layer "F.SilkS")
		)
		(fp_line
			(start -0.7874 -0.4064)
			(end 0.7874 -0.4064)
			(stroke
				(width 0.1524)
				(type default)
			)
			(layer "F.SilkS")
		)
		(fp_line
			(start 0.7874 -0.4064)
			(end 0.7874 0.4064)
			(stroke
				(width 0.1524)
				(type default)
			)
			(layer "F.SilkS")
		)
		(fp_line
			(start -0.67945 0.3048)
			(end -0.67945 -0.305054)
			(stroke
				(width 0.1)
				(type default)
			)
			(layer "F.Fab")
		)
		(fp_line
			(start -0.12065 0.3048)
			(end -0.67945 0.3048)
			(stroke
				(width 0.1)
				(type default)
			)
			(layer "F.Fab")
		)
		(fp_line
			(start 0.120396 0.3048)
			(end 0.120396 0.2794)
			(stroke
				(width 0.1)
				(type default)
			)
			(layer "F.Fab")
		)
		(fp_line
			(start 0.67945 0.3048)
			(end 0.120396 0.3048)
			(stroke
				(width 0.1)
				(type default)
			)
			(layer "F.Fab")
		)
		(fp_line
			(start -0.12065 0.2794)
			(end -0.12065 0.3048)
			(stroke
				(width 0.1)
				(type default)
			)
			(layer "F.Fab")
		)
		(fp_line
			(start 0.120396 0.2794)
			(end -0.12065 0.2794)
			(stroke
				(width 0.1)
				(type default)
			)
			(layer "F.Fab")
		)
		(fp_line
			(start -0.12065 -0.2794)
			(end 0.12065 -0.2794)
			(stroke
				(width 0.1)
				(type default)
			)
			(layer "F.Fab")
		)
		(fp_line
			(start 0.12065 -0.2794)
			(end 0.12065 -0.3048)
			(stroke
				(width 0.1)
				(type default)
			)
			(layer "F.Fab")
		)
		(fp_line
			(start 0.12065 -0.3048)
			(end 0.67945 -0.3048)
			(stroke
				(width 0.1)
				(type default)
			)
			(layer "F.Fab")
		)
		(fp_line
			(start 0.67945 -0.3048)
			(end 0.67945 0.3048)
			(stroke
				(width 0.1)
				(type default)
			)
			(layer "F.Fab")
		)
		(fp_line
			(start -0.67945 -0.305054)
			(end -0.12065 -0.305054)
			(stroke
				(width 0.1)
				(type default)
			)
			(layer "F.Fab")
		)
		(fp_line
			(start -0.12065 -0.305054)
			(end -0.12065 -0.2794)
			(stroke
				(width 0.1)
				(type default)
			)
			(layer "F.Fab")
		)
		(pad "1" smd circle
			(at -0.40005 0 270)
			(size 0 0)
			(layers "F.Cu" "F.Mask" "F.Paste")
			(net "P1V8_STBY_PE_VCC18A")
		)
		(pad "2" smd circle
			(at 0.40005 0 270)
			(size 0 0)
			(layers "F.Cu" "F.Mask" "F.Paste")
			(net "GND")
		)
	)
)
